(kicad_pcb
	(version 20241229)
	(generator "pcbnew")
	(generator_version "9.0")
	(general
		(thickness 1.294)
		(legacy_teardrops no)
	)
	(paper "A3")
	(title_block
		(title "Kintex 410T devboard")
		(date "2024-04-03")
		(rev "1.1.2")
		(comment 9 "footprints 513-516 of 975")
	)
	(layers
		(0 "F.Cu" mixed)
		(4 "In1.Cu" power)
		(6 "In2.Cu" power)
		(8 "In3.Cu" mixed)
		(10 "In4.Cu" power)
		(12 "In5.Cu" mixed)
		(14 "In6.Cu" power)
		(16 "In7.Cu" mixed)
		(18 "In8.Cu" power)
		(2 "B.Cu" mixed)
		(9 "F.Adhes" user "F.Adhesive")
		(11 "B.Adhes" user "B.Adhesive")
		(13 "F.Paste" user)
		(15 "B.Paste" user)
		(5 "F.SilkS" user "F.Silkscreen")
		(7 "B.SilkS" user "B.Silkscreen")
		(1 "F.Mask" user)
		(3 "B.Mask" user)
		(17 "Dwgs.User" user "User.Drawings")
		(19 "Cmts.User" user "User.Comments")
		(21 "Eco1.User" user "User.Eco1")
		(23 "Eco2.User" user "User.Eco2")
		(25 "Edge.Cuts" user)
		(27 "Margin" user)
		(31 "F.CrtYd" user "F.Courtyard")
		(29 "B.CrtYd" user "B.Courtyard")
		(35 "F.Fab" user)
		(33 "B.Fab" user)
	)
	(footprint "antmicro-footprints:R_0402_1005Metric"
		(layer "B.Cu")
		(at 193.1 84.8 90)
		(descr "Resistor SMD 0402")
		(tags "resistor SMD 0402")
		(property "Reference" "R139"
			(at -0.725 0.4 270)
			(layer "B.SilkS")
			(effects
				(font
					(size 0.7 0.7)
					(thickness 0.15)
				)
				(justify left bottom mirror)
			)
		)
		(property "Value" "R_100R_0402"
			(at 0 -1.4 270)
			(layer "B.Fab")
			(effects
				(font
					(size 0.7 0.7)
					(thickness 0.15)
				)
				(justify left bottom mirror)
			)
		)
		(property "Description" "SMD Chip Resistor, 100 ohm, ± 1%, 62.5 mW, 0402 [1005 Metric], Thick Film, General Purpose"
			(at 0 0 90)
			(layer "F.Fab")
			(hide yes)
			(effects
				(font
					(size 1.27 1.27)
					(thickness 0.15)
				)
			)
		)
		(property "Author" "Antmicro"
			(at 277.9 -108.3 0)
			(layer "B.Fab")
			(hide yes)
			(effects
				(font
					(size 1 1)
					(thickness 0.15)
				)
				(justify mirror)
			)
		)
		(property "License" "Apache-2.0"
			(at 277.9 -108.3 0)
			(layer "B.Fab")
			(hide yes)
			(effects
				(font
					(size 1 1)
					(thickness 0.15)
				)
				(justify mirror)
			)
		)
		(property "MPN" "CR0402-FX-1000GLF"
			(at 277.9 -108.3 0)
			(layer "B.Fab")
			(hide yes)
			(effects
				(font
					(size 1 1)
					(thickness 0.15)
				)
				(justify mirror)
			)
		)
		(property "Manufacturer" "Bourns"
			(at 277.9 -108.3 0)
			(layer "B.Fab")
			(hide yes)
			(effects
				(font
					(size 1 1)
					(thickness 0.15)
				)
				(justify mirror)
			)
		)
		(property "Tolerance" "1%"
			(at 277.9 -108.3 0)
			(layer "B.Fab")
			(hide yes)
			(effects
				(font
					(size 1 1)
					(thickness 0.15)
				)
				(justify mirror)
			)
		)
		(property "Val" "100R"
			(at 277.9 -108.3 0)
			(layer "B.Fab")
			(hide yes)
			(effects
				(font
					(size 1 1)
					(thickness 0.15)
				)
				(justify mirror)
			)
		)
		(sheetname "User GPIO + LED + button + DIP switch")
		(sheetfile "user-gpio.kicad_sch")
		(attr smd)
		(fp_rect
			(start -0.925 0.47)
			(end 0.925 -0.47)
			(stroke
				(width 0.05)
				(type default)
			)
			(fill no)
			(layer "B.CrtYd")
		)
		(fp_rect
			(start -0.5 0.25)
			(end 0.5 -0.25)
			(stroke
				(width 0.15)
				(type solid)
			)
			(fill no)
			(layer "B.Fab")
		)
		(pad "1" smd roundrect
			(at -0.48 0 90)
			(size 0.59 0.64)
			(layers "B.Cu" "B.Mask" "B.Paste")
			(roundrect_rratio 0.25)
			(net 832 "/User GPIO + LED + button + DIP switch/CW_20PIN_TPDID")
			(pintype "passive")
		)
		(pad "2" smd roundrect
			(at 0.48 0 90)
			(size 0.59 0.64)
			(layers "B.Cu" "B.Mask" "B.Paste")
			(roundrect_rratio 0.25)
			(net 485 "/FPGA Bank 12 & 13/CW_HEADER.TPDID")
			(pintype "passive")
		)
	)
	(footprint "antmicro-footprints:R_Array_4x0201_Panasonic_EXB18V"
		(layer "B.Cu")
		(at 251.901 149.15)
		(property "Reference" "R31"
			(at 1.024 1.525 0)
			(layer "B.SilkS")
			(effects
				(font
					(size 0.7 0.7)
					(thickness 0.15)
				)
				(justify left bottom mirror)
			)
		)
		(property "Value" "R_4x33R_0201_array"
			(at -1.1 -1.8 0)
			(layer "B.Fab")
			(effects
				(font
					(size 0.7 0.7)
					(thickness 0.15)
				)
				(justify right bottom mirror)
			)
		)
		(property "Description" "Fixed Network Resistor, 33 ohm, Isolated, 4 Resistors, 0502 [1406 Metric], Flat, ± 5%"
			(at 0 0 0)
			(layer "F.Fab")
			(hide yes)
			(effects
				(font
					(size 1.27 1.27)
					(thickness 0.15)
				)
			)
		)
		(property "Author" "Antmicro"
			(at 0 0 0)
			(layer "B.Fab")
			(hide yes)
			(effects
				(font
					(size 1 1)
					(thickness 0.15)
				)
				(justify mirror)
			)
		)
		(property "License" "Apache-2.0"
			(at 0 0 0)
			(layer "B.Fab")
			(hide yes)
			(effects
				(font
					(size 1 1)
					(thickness 0.15)
				)
				(justify mirror)
			)
		)
		(property "MPN" "EXB-18V330JX"
			(at 0 0 0)
			(layer "B.Fab")
			(hide yes)
			(effects
				(font
					(size 1 1)
					(thickness 0.15)
				)
				(justify mirror)
			)
		)
		(property "Manufacturer" "Panasonic"
			(at 0 0 0)
			(layer "B.Fab")
			(hide yes)
			(effects
				(font
					(size 1 1)
					(thickness 0.15)
				)
				(justify mirror)
			)
		)
		(property "Val" "R_4x33R_0201"
			(at 0 0 0)
			(layer "B.Fab")
			(hide yes)
			(effects
				(font
					(size 1 1)
					(thickness 0.15)
				)
				(justify mirror)
			)
		)
		(sheetname "Supervisior MCU")
		(sheetfile "supervisor-mcu.kicad_sch")
		(attr smd)
		(fp_line
			(start -0.8 0.45)
			(end -0.8 -0.45)
			(stroke
				(width 0.12)
				(type solid)
			)
			(layer "B.SilkS")
		)
		(fp_line
			(start 0.8 0.45)
			(end 0.8 -0.45)
			(stroke
				(width 0.12)
				(type solid)
			)
			(layer "B.SilkS")
		)
		(fp_rect
			(start -0.898 0.66)
			(end 0.898 -0.65)
			(stroke
				(width 0.05)
				(type solid)
			)
			(fill no)
			(layer "B.CrtYd")
		)
		(pad "1" smd roundrect
			(at -0.6 -0.298)
			(size 0.2 0.4)
			(layers "B.Cu" "B.Mask" "B.Paste")
			(roundrect_rratio 0.25)
			(net 1413 "/SUP_MCU.PG_1V2")
			(pinfunction "R1.1")
			(pintype "passive")
		)
		(pad "2" smd roundrect
			(at -0.202 -0.298)
			(size 0.2 0.4)
			(layers "B.Cu" "B.Mask" "B.Paste")
			(roundrect_rratio 0.25)
			(net 1314 "/SUP_MCU.FPGA_M2")
			(pinfunction "R2.1")
			(pintype "passive")
		)
		(pad "3" smd roundrect
			(at 0.2 -0.298)
			(size 0.2 0.4)
			(layers "B.Cu" "B.Mask" "B.Paste")
			(roundrect_rratio 0.25)
			(net 1378 "/SUP_MCU.A8")
			(pinfunction "R3.1")
			(pintype "passive")
		)
		(pad "4" smd roundrect
			(at 0.598 -0.298)
			(size 0.2 0.4)
			(layers "B.Cu" "B.Mask" "B.Paste")
			(roundrect_rratio 0.25)
			(net 1321 "/SUP_MCU.MOSI")
			(pinfunction "R4.1")
			(pintype "passive")
		)
		(pad "5" smd roundrect
			(at 0.598 0.3)
			(size 0.2 0.4)
			(layers "B.Cu" "B.Mask" "B.Paste")
			(roundrect_rratio 0.25)
			(net 1090 "/Supervisior MCU/USB_SPI_COPI")
			(pinfunction "R4.2")
			(pintype "passive")
		)
		(pad "6" smd roundrect
			(at 0.2 0.3)
			(size 0.2 0.4)
			(layers "B.Cu" "B.Mask" "B.Paste")
			(roundrect_rratio 0.25)
			(net 1069 "/Supervisior MCU/USB_A8")
			(pinfunction "R3.2")
			(pintype "passive")
		)
		(pad "7" smd roundrect
			(at -0.202 0.3)
			(size 0.2 0.4)
			(layers "B.Cu" "B.Mask" "B.Paste")
			(roundrect_rratio 0.25)
			(net 1105 "/Supervisior MCU/FPGA_M2")
			(pinfunction "R2.2")
			(pintype "passive")
		)
		(pad "8" smd roundrect
			(at -0.6 0.3)
			(size 0.2 0.4)
			(layers "B.Cu" "B.Mask" "B.Paste")
			(roundrect_rratio 0.25)
			(net 1088 "/Supervisior MCU/PGOOD_1V2")
			(pinfunction "R1.2")
			(pintype "passive")
		)
	)
	(footprint "antmicro-footprints:R_Array_4x0201_Panasonic_EXB18V"
		(layer "B.Cu")
		(at 245.901 149.15)
		(property "Reference" "R28"
			(at 1.074 -0.675 0)
			(layer "B.SilkS")
			(effects
				(font
					(size 0.7 0.7)
					(thickness 0.15)
				)
				(justify left bottom mirror)
			)
		)
		(property "Value" "R_4x33R_0201_array"
			(at -1.1 -1.8 0)
			(layer "B.Fab")
			(effects
				(font
					(size 0.7 0.7)
					(thickness 0.15)
				)
				(justify right bottom mirror)
			)
		)
		(property "Description" "Fixed Network Resistor, 33 ohm, Isolated, 4 Resistors, 0502 [1406 Metric], Flat, ± 5%"
			(at 0 0 0)
			(layer "F.Fab")
			(hide yes)
			(effects
				(font
					(size 1.27 1.27)
					(thickness 0.15)
				)
			)
		)
		(property "Author" "Antmicro"
			(at 0 0 0)
			(layer "B.Fab")
			(hide yes)
			(effects
				(font
					(size 1 1)
					(thickness 0.15)
				)
				(justify mirror)
			)
		)
		(property "License" "Apache-2.0"
			(at 0 0 0)
			(layer "B.Fab")
			(hide yes)
			(effects
				(font
					(size 1 1)
					(thickness 0.15)
				)
				(justify mirror)
			)
		)
		(property "MPN" "EXB-18V330JX"
			(at 0 0 0)
			(layer "B.Fab")
			(hide yes)
			(effects
				(font
					(size 1 1)
					(thickness 0.15)
				)
				(justify mirror)
			)
		)
		(property "Manufacturer" "Panasonic"
			(at 0 0 0)
			(layer "B.Fab")
			(hide yes)
			(effects
				(font
					(size 1 1)
					(thickness 0.15)
				)
				(justify mirror)
			)
		)
		(property "Val" "R_4x33R_0201"
			(at 0 0 0)
			(layer "B.Fab")
			(hide yes)
			(effects
				(font
					(size 1 1)
					(thickness 0.15)
				)
				(justify mirror)
			)
		)
		(sheetname "Supervisior MCU")
		(sheetfile "supervisor-mcu.kicad_sch")
		(attr smd)
		(fp_line
			(start -0.8 0.45)
			(end -0.8 -0.45)
			(stroke
				(width 0.12)
				(type solid)
			)
			(layer "B.SilkS")
		)
		(fp_line
			(start 0.8 0.45)
			(end 0.8 -0.45)
			(stroke
				(width 0.12)
				(type solid)
			)
			(layer "B.SilkS")
		)
		(fp_rect
			(start -0.898 0.66)
			(end 0.898 -0.65)
			(stroke
				(width 0.05)
				(type solid)
			)
			(fill no)
			(layer "B.CrtYd")
		)
		(pad "1" smd roundrect
			(at -0.6 -0.298)
			(size 0.2 0.4)
			(layers "B.Cu" "B.Mask" "B.Paste")
			(roundrect_rratio 0.25)
			(net 358 "unconnected-(R28-R1.1-Pad1)")
			(pinfunction "R1.1")
			(pintype "passive+no_connect")
		)
		(pad "2" smd roundrect
			(at -0.202 -0.298)
			(size 0.2 0.4)
			(layers "B.Cu" "B.Mask" "B.Paste")
			(roundrect_rratio 0.25)
			(net 359 "unconnected-(R28-R2.1-Pad2)")
			(pinfunction "R2.1")
			(pintype "passive+no_connect")
		)
		(pad "3" smd roundrect
			(at 0.2 -0.298)
			(size 0.2 0.4)
			(layers "B.Cu" "B.Mask" "B.Paste")
			(roundrect_rratio 0.25)
			(net 1372 "/SUP_MCU.D0")
			(pinfunction "R3.1")
			(pintype "passive")
		)
		(pad "4" smd roundrect
			(at 0.598 -0.298)
			(size 0.2 0.4)
			(layers "B.Cu" "B.Mask" "B.Paste")
			(roundrect_rratio 0.25)
			(net 1373 "/SUP_MCU.D3")
			(pinfunction "R4.1")
			(pintype "passive")
		)
		(pad "5" smd roundrect
			(at 0.598 0.3)
			(size 0.2 0.4)
			(layers "B.Cu" "B.Mask" "B.Paste")
			(roundrect_rratio 0.25)
			(net 1109 "/Supervisior MCU/USB_D3")
			(pinfunction "R4.2")
			(pintype "passive")
		)
		(pad "6" smd roundrect
			(at 0.2 0.3)
			(size 0.2 0.4)
			(layers "B.Cu" "B.Mask" "B.Paste")
			(roundrect_rratio 0.25)
			(net 1099 "/Supervisior MCU/USB_D0")
			(pinfunction "R3.2")
			(pintype "passive")
		)
		(pad "7" smd roundrect
			(at -0.202 0.3)
			(size 0.2 0.4)
			(layers "B.Cu" "B.Mask" "B.Paste")
			(roundrect_rratio 0.25)
			(net 360 "unconnected-(R28-R2.2-Pad7)")
			(pinfunction "R2.2")
			(pintype "passive+no_connect")
		)
		(pad "8" smd roundrect
			(at -0.6 0.3)
			(size 0.2 0.4)
			(layers "B.Cu" "B.Mask" "B.Paste")
			(roundrect_rratio 0.25)
			(net 361 "unconnected-(R28-R1.2-Pad8)")
			(pinfunction "R1.2")
			(pintype "passive+no_connect")
		)
	)
	(footprint "antmicro-footprints:C_0402_1005Metric"
		(layer "B.Cu")
		(at 157.65 144.5 -90)
		(descr "Capacitor SMD 0402")
		(tags "capacitor SMD 0402")
		(property "Reference" "C175"
			(at -1.9 3.475 90)
			(layer "B.SilkS")
			(effects
				(font
					(size 0.7 0.7)
					(thickness 0.15)
				)
				(justify left bottom mirror)
			)
		)
		(property "Value" "C_100n_0402"
			(at 0 -1.169 90)
			(layer "B.Fab")
			(effects
				(font
					(size 0.7 0.7)
					(thickness 0.15)
				)
				(justify left bottom mirror)
			)
		)
		(property "Description" "SMD Multilayer Ceramic Capacitor, 0.1 µF, 50 V, 0402 [1005 Metric], ± 10%, X5R, GRM Series"
			(at 0 0 270)
			(layer "F.Fab")
			(hide yes)
			(effects
				(font
					(size 1.27 1.27)
					(thickness 0.15)
				)
			)
		)
		(property "Author" "Antmicro"
			(at 13.15 302.15 0)
			(layer "B.Fab")
			(hide yes)
			(effects
				(font
					(size 1 1)
					(thickness 0.15)
				)
				(justify mirror)
			)
		)
		(property "Dielectric" "X5R"
			(at 13.15 302.15 0)
			(layer "B.Fab")
			(hide yes)
			(effects
				(font
					(size 1 1)
					(thickness 0.15)
				)
				(justify mirror)
			)
		)
		(property "License" "Apache-2.0"
			(at 13.15 302.15 0)
			(layer "B.Fab")
			(hide yes)
			(effects
				(font
					(size 1 1)
					(thickness 0.15)
				)
				(justify mirror)
			)
		)
		(property "MPN" "GRM155R61H104KE14D"
			(at 13.15 302.15 0)
			(layer "B.Fab")
			(hide yes)
			(effects
				(font
					(size 1 1)
					(thickness 0.15)
				)
				(justify mirror)
			)
		)
		(property "Manufacturer" "Murata"
			(at 13.15 302.15 0)
			(layer "B.Fab")
			(hide yes)
			(effects
				(font
					(size 1 1)
					(thickness 0.15)
				)
				(justify mirror)
			)
		)
		(property "Val" "100n"
			(at 13.15 302.15 0)
			(layer "B.Fab")
			(hide yes)
			(effects
				(font
					(size 1 1)
					(thickness 0.15)
				)
				(justify mirror)
			)
		)
		(property "Voltage" "50V"
			(at 13.15 302.15 0)
			(layer "B.Fab")
			(hide yes)
			(effects
				(font
					(size 1 1)
					(thickness 0.15)
				)
				(justify mirror)
			)
		)
		(sheetname "DRAM + SRAM")
		(sheetfile "ram.kicad_sch")
		(attr smd)
		(fp_rect
			(start -0.925 0.47)
			(end 0.925 -0.47)
			(stroke
				(width 0.05)
				(type default)
			)
			(fill no)
			(layer "B.CrtYd")
		)
		(fp_line
			(start -0.494 0.25)
			(end 0.504 0.25)
			(stroke
				(width 0.15)
				(type solid)
			)
			(layer "B.Fab")
		)
		(fp_line
			(start 0.504 0.25)
			(end 0.504 -0.248)
			(stroke
				(width 0.15)
				(type solid)
			)
			(layer "B.Fab")
		)
		(fp_line
			(start -0.494 -0.248)
			(end -0.494 0.25)
			(stroke
				(width 0.15)
				(type solid)
			)
			(layer "B.Fab")
		)
		(fp_line
			(start 0.504 -0.248)
			(end -0.494 -0.248)
			(stroke
				(width 0.15)
				(type solid)
			)
			(layer "B.Fab")
		)
		(pad "1" smd roundrect
			(at -0.48 0 270)
			(size 0.59 0.64)
			(layers "B.Cu" "B.Mask" "B.Paste")
			(roundrect_rratio 0.25)
			(net 1 "GND")
			(pintype "passive")
		)
		(pad "2" smd roundrect
			(at 0.48 0 270)
			(size 0.59 0.64)
			(layers "B.Cu" "B.Mask" "B.Paste")
			(roundrect_rratio 0.25)
			(net 7 "+0V675_VTT")
			(pintype "passive")
		)
	)
)
